G04 CAM350 V10.2.1 (Build 391) Date:  Fri Dec 30 15:05:17 2016 *
G04 Database: (Untitled) *
G04 Layer 4: BSMD.art *
%FSLAX35Y35*%
%MOIN*%
%SFA1.000B1.000*%

%MIA0B0*%
%IPPOS*%
%AMMACRO14*
4,1,40,-0.01100,-0.00700,-0.01100,0.00700,-0.01094,0.00770,-0.01076,0.00837,-0.01046,0.00900,-0.01006,0.00957,-0.00957,0.01006,-0.00900,0.01046,-0.00837,0.01076,-0.00769,0.01094,-0.00700,0.01100,0.00700,0.01100,0.00770,0.01094,0.00837,0.01076,0.00900,0.01046,0.00957,0.01006,0.01006,0.00957,0.01046,0.00900,0.01076,0.00837,0.01094,0.00770,0.01100,0.00700,0.01100,-0.00700,0.01094,-0.00769,0.01076,-0.00837,0.01046,-0.00900,0.01006,-0.00957,0.00957,-0.01006,0.00900,-0.01046,0.00837,-0.01076,0.00770,-0.01094,0.00700,-0.01100,-0.00700,-0.01100,-0.00769,-0.01094,-0.00837,-0.01076,-0.00900,-0.01046,-0.00957,-0.01006,-0.01006,-0.00957,-0.01046,-0.00900,-0.01076,-0.00837,-0.01094,-0.00769,-0.01100,-0.00700,0.00000*
%
%AMMACRO17*
4,1,40,0.01100,0.00700,0.01100,-0.00700,0.01094,-0.00769,0.01076,-0.00837,0.01046,-0.00900,0.01006,-0.00957,0.00957,-0.01006,0.00900,-0.01046,0.00837,-0.01076,0.00770,-0.01094,0.00700,-0.01100,-0.00700,-0.01100,-0.00769,-0.01094,-0.00837,-0.01076,-0.00900,-0.01046,-0.00957,-0.01006,-0.01006,-0.00957,-0.01046,-0.00900,-0.01076,-0.00837,-0.01094,-0.00769,-0.01100,-0.00700,-0.01100,0.00700,-0.01094,0.00770,-0.01076,0.00837,-0.01046,0.00900,-0.01006,0.00957,-0.00957,0.01006,-0.00900,0.01046,-0.00837,0.01076,-0.00769,0.01094,-0.00700,0.01100,0.00700,0.01100,0.00770,0.01094,0.00837,0.01076,0.00900,0.01046,0.00957,0.01006,0.01006,0.00957,0.01046,0.00900,0.01076,0.00837,0.01094,0.00770,0.01100,0.00700,0.00000*
%
%AMMACRO18*
4,1,40,0.00700,-0.01100,-0.00700,-0.01100,-0.00769,-0.01094,-0.00837,-0.01076,-0.00900,-0.01046,-0.00957,-0.01006,-0.01006,-0.00957,-0.01046,-0.00900,-0.01076,-0.00837,-0.01094,-0.00769,-0.01100,-0.00700,-0.01100,0.00700,-0.01094,0.00770,-0.01076,0.00837,-0.01046,0.00900,-0.01006,0.00957,-0.00957,0.01006,-0.00900,0.01046,-0.00837,0.01076,-0.00769,0.01094,-0.00700,0.01100,0.00700,0.01100,0.00770,0.01094,0.00837,0.01076,0.00900,0.01046,0.00957,0.01006,0.01006,0.00957,0.01046,0.00900,0.01076,0.00837,0.01094,0.00770,0.01100,0.00700,0.01100,-0.00700,0.01094,-0.00769,0.01076,-0.00837,0.01046,-0.00900,0.01006,-0.00957,0.00957,-0.01006,0.00900,-0.01046,0.00837,-0.01076,0.00770,-0.01094,0.00700,-0.01100,0.00000*
%
%AMMACRO20*
4,1,40,-0.00700,0.01100,0.00700,0.01100,0.00770,0.01094,0.00837,0.01076,0.00900,0.01046,0.00957,0.01006,0.01006,0.00957,0.01046,0.00900,0.01076,0.00837,0.01094,0.00770,0.01100,0.00700,0.01100,-0.00700,0.01094,-0.00769,0.01076,-0.00837,0.01046,-0.00900,0.01006,-0.00957,0.00957,-0.01006,0.00900,-0.01046,0.00837,-0.01076,0.00770,-0.01094,0.00700,-0.01100,-0.00700,-0.01100,-0.00769,-0.01094,-0.00837,-0.01076,-0.00900,-0.01046,-0.00957,-0.01006,-0.01006,-0.00957,-0.01046,-0.00900,-0.01076,-0.00837,-0.01094,-0.00769,-0.01100,-0.00700,-0.01100,0.00700,-0.01094,0.00770,-0.01076,0.00837,-0.01046,0.00900,-0.01006,0.00957,-0.00957,0.01006,-0.00900,0.01046,-0.00837,0.01076,-0.00769,0.01094,-0.00700,0.01100,0.00000*
%
%AMMACRO24*
4,1,40,0.01300,-0.01700,-0.01300,-0.01700,-0.01369,-0.01694,-0.01437,-0.01676,-0.01500,-0.01646,-0.01557,-0.01606,-0.01606,-0.01557,-0.01646,-0.01500,-0.01676,-0.01437,-0.01694,-0.01369,-0.01700,-0.01300,-0.01700,0.01300,-0.01694,0.01370,-0.01676,0.01437,-0.01646,0.01500,-0.01606,0.01557,-0.01557,0.01606,-0.01500,0.01646,-0.01437,0.01676,-0.01369,0.01694,-0.01300,0.01700,0.01300,0.01700,0.01370,0.01694,0.01437,0.01676,0.01500,0.01646,0.01557,0.01606,0.01606,0.01557,0.01646,0.01500,0.01676,0.01437,0.01694,0.01370,0.01700,0.01300,0.01700,-0.01300,0.01694,-0.01369,0.01676,-0.01437,0.01646,-0.01500,0.01606,-0.01557,0.01557,-0.01606,0.01500,-0.01646,0.01437,-0.01676,0.01370,-0.01694,0.01300,-0.01700,0.00000*
%
%AMMACRO26*
4,1,40,-0.00800,0.01200,0.00800,0.01200,0.00870,0.01194,0.00937,0.01176,0.01000,0.01146,0.01057,0.01106,0.01106,0.01057,0.01146,0.01000,0.01176,0.00937,0.01194,0.00870,0.01200,0.00800,0.01200,-0.00800,0.01194,-0.00869,0.01176,-0.00937,0.01146,-0.01000,0.01106,-0.01057,0.01057,-0.01106,0.01000,-0.01146,0.00937,-0.01176,0.00870,-0.01194,0.00800,-0.01200,-0.00800,-0.01200,-0.00869,-0.01194,-0.00937,-0.01176,-0.01000,-0.01146,-0.01057,-0.01106,-0.01106,-0.01057,-0.01146,-0.01000,-0.01176,-0.00937,-0.01194,-0.00869,-0.01200,-0.00800,-0.01200,0.00800,-0.01194,0.00870,-0.01176,0.00937,-0.01146,0.01000,-0.01106,0.01057,-0.01057,0.01106,-0.01000,0.01146,-0.00937,0.01176,-0.00869,0.01194,-0.00800,0.01200,0.00000*
%
%AMMACRO27*
4,1,40,-0.01300,0.01700,0.01300,0.01700,0.01370,0.01694,0.01437,0.01676,0.01500,0.01646,0.01557,0.01606,0.01606,0.01557,0.01646,0.01500,0.01676,0.01437,0.01694,0.01370,0.01700,0.01300,0.01700,-0.01300,0.01694,-0.01369,0.01676,-0.01437,0.01646,-0.01500,0.01606,-0.01557,0.01557,-0.01606,0.01500,-0.01646,0.01437,-0.01676,0.01370,-0.01694,0.01300,-0.01700,-0.01300,-0.01700,-0.01369,-0.01694,-0.01437,-0.01676,-0.01500,-0.01646,-0.01557,-0.01606,-0.01606,-0.01557,-0.01646,-0.01500,-0.01676,-0.01437,-0.01694,-0.01369,-0.01700,-0.01300,-0.01700,0.01300,-0.01694,0.01370,-0.01676,0.01437,-0.01646,0.01500,-0.01606,0.01557,-0.01557,0.01606,-0.01500,0.01646,-0.01437,0.01676,-0.01369,0.01694,-0.01300,0.01700,0.00000*
%
%AMMACRO13*
4,1,40,-0.01100,-0.00700,-0.01100,0.00700,-0.01094,0.00770,-0.01076,0.00837,-0.01046,0.00900,-0.01006,0.00957,-0.00957,0.01006,-0.00900,0.01046,-0.00837,0.01076,-0.00769,0.01094,-0.00700,0.01100,0.00700,0.01100,0.00770,0.01094,0.00837,0.01076,0.00900,0.01046,0.00957,0.01006,0.01006,0.00957,0.01046,0.00900,0.01076,0.00837,0.01094,0.00770,0.01100,0.00700,0.01100,-0.00700,0.01094,-0.00769,0.01076,-0.00837,0.01046,-0.00900,0.01006,-0.00957,0.00957,-0.01006,0.00900,-0.01046,0.00837,-0.01076,0.00770,-0.01094,0.00700,-0.01100,-0.00700,-0.01100,-0.00769,-0.01094,-0.00837,-0.01076,-0.00900,-0.01046,-0.00957,-0.01006,-0.01006,-0.00957,-0.01046,-0.00900,-0.01076,-0.00837,-0.01094,-0.00769,-0.01100,-0.00700,0.00000*
%
%AMMACRO29*
4,1,40,0.01200,0.00800,0.01200,-0.00800,0.01194,-0.00869,0.01176,-0.00937,0.01146,-0.01000,0.01106,-0.01057,0.01057,-0.01106,0.01000,-0.01146,0.00937,-0.01176,0.00870,-0.01194,0.00800,-0.01200,-0.00800,-0.01200,-0.00869,-0.01194,-0.00937,-0.01176,-0.01000,-0.01146,-0.01057,-0.01106,-0.01106,-0.01057,-0.01146,-0.01000,-0.01176,-0.00937,-0.01194,-0.00869,-0.01200,-0.00800,-0.01200,0.00800,-0.01194,0.00870,-0.01176,0.00937,-0.01146,0.01000,-0.01106,0.01057,-0.01057,0.01106,-0.01000,0.01146,-0.00937,0.01176,-0.00869,0.01194,-0.00800,0.01200,0.00800,0.01200,0.00870,0.01194,0.00937,0.01176,0.01000,0.01146,0.01057,0.01106,0.01106,0.01057,0.01146,0.01000,0.01176,0.00937,0.01194,0.00870,0.01200,0.00800,0.00000*
%
%AMMACRO22*
4,1,40,0.01300,-0.01700,-0.01300,-0.01700,-0.01369,-0.01694,-0.01437,-0.01676,-0.01500,-0.01646,-0.01557,-0.01606,-0.01606,-0.01557,-0.01646,-0.01500,-0.01676,-0.01437,-0.01694,-0.01369,-0.01700,-0.01300,-0.01700,0.01300,-0.01694,0.01370,-0.01676,0.01437,-0.01646,0.01500,-0.01606,0.01557,-0.01557,0.01606,-0.01500,0.01646,-0.01437,0.01676,-0.01369,0.01694,-0.01300,0.01700,0.01300,0.01700,0.01370,0.01694,0.01437,0.01676,0.01500,0.01646,0.01557,0.01606,0.01606,0.01557,0.01646,0.01500,0.01676,0.01437,0.01694,0.01370,0.01700,0.01300,0.01700,-0.01300,0.01694,-0.01369,0.01676,-0.01437,0.01646,-0.01500,0.01606,-0.01557,0.01557,-0.01606,0.01500,-0.01646,0.01437,-0.01676,0.01370,-0.01694,0.01300,-0.01700,0.00000*
%
%AMMACRO31*
4,1,40,0.01200,0.00800,0.01200,-0.00800,0.01194,-0.00869,0.01176,-0.00937,0.01146,-0.01000,0.01106,-0.01057,0.01057,-0.01106,0.01000,-0.01146,0.00937,-0.01176,0.00870,-0.01194,0.00800,-0.01200,-0.00800,-0.01200,-0.00869,-0.01194,-0.00937,-0.01176,-0.01000,-0.01146,-0.01057,-0.01106,-0.01106,-0.01057,-0.01146,-0.01000,-0.01176,-0.00937,-0.01194,-0.00869,-0.01200,-0.00800,-0.01200,0.00800,-0.01194,0.00870,-0.01176,0.00937,-0.01146,0.01000,-0.01106,0.01057,-0.01057,0.01106,-0.01000,0.01146,-0.00937,0.01176,-0.00869,0.01194,-0.00800,0.01200,0.00800,0.01200,0.00870,0.01194,0.00937,0.01176,0.01000,0.01146,0.01057,0.01106,0.01106,0.01057,0.01146,0.01000,0.01176,0.00937,0.01194,0.00870,0.01200,0.00800,0.00000*
%
%AMMACRO20_180*
4,1,40,0.00700,-0.01100,-0.00700,-0.01100,-0.00770,-0.01094,-0.00837,-0.01076,-0.00900,-0.01046,-0.00957,-0.01006,-0.01006,-0.00957,-0.01046,-0.00900,-0.01076,-0.00837,-0.01094,-0.00770,-0.01100,-0.00700,-0.01100,0.00700,-0.01094,0.00769,-0.01076,0.00837,-0.01046,0.00900,-0.01006,0.00957,-0.00957,0.01006,-0.00900,0.01046,-0.00837,0.01076,-0.00770,0.01094,-0.00700,0.01100,0.00700,0.01100,0.00769,0.01094,0.00837,0.01076,0.00900,0.01046,0.00957,0.01006,0.01006,0.00957,0.01046,0.00900,0.01076,0.00837,0.01094,0.00769,0.01100,0.00700,0.01100,-0.00700,0.01094,-0.00770,0.01076,-0.00837,0.01046,-0.00900,0.01006,-0.00957,0.00957,-0.01006,0.00900,-0.01046,0.00837,-0.01076,0.00769,-0.01094,0.00700,-0.01100,0.00000*
%
%AMMACRO14_180*
4,1,40,0.01100,0.00700,0.01100,-0.00700,0.01094,-0.00770,0.01076,-0.00837,0.01046,-0.00900,0.01006,-0.00957,0.00957,-0.01006,0.00900,-0.01046,0.00837,-0.01076,0.00769,-0.01094,0.00700,-0.01100,-0.00700,-0.01100,-0.00770,-0.01094,-0.00837,-0.01076,-0.00900,-0.01046,-0.00957,-0.01006,-0.01006,-0.00957,-0.01046,-0.00900,-0.01076,-0.00837,-0.01094,-0.00770,-0.01100,-0.00700,-0.01100,0.00700,-0.01094,0.00769,-0.01076,0.00837,-0.01046,0.00900,-0.01006,0.00957,-0.00957,0.01006,-0.00900,0.01046,-0.00837,0.01076,-0.00770,0.01094,-0.00700,0.01100,0.00700,0.01100,0.00769,0.01094,0.00837,0.01076,0.00900,0.01046,0.00957,0.01006,0.01006,0.00957,0.01046,0.00900,0.01076,0.00837,0.01094,0.00769,0.01100,0.00700,0.00000*
%
%AMMACRO24_180*
4,1,40,-0.01300,0.01700,0.01300,0.01700,0.01369,0.01694,0.01437,0.01676,0.01500,0.01646,0.01557,0.01606,0.01606,0.01557,0.01646,0.01500,0.01676,0.01437,0.01694,0.01369,0.01700,0.01300,0.01700,-0.01300,0.01694,-0.01370,0.01676,-0.01437,0.01646,-0.01500,0.01606,-0.01557,0.01557,-0.01606,0.01500,-0.01646,0.01437,-0.01676,0.01369,-0.01694,0.01300,-0.01700,-0.01300,-0.01700,-0.01370,-0.01694,-0.01437,-0.01676,-0.01500,-0.01646,-0.01557,-0.01606,-0.01606,-0.01557,-0.01646,-0.01500,-0.01676,-0.01437,-0.01694,-0.01370,-0.01700,-0.01300,-0.01700,0.01300,-0.01694,0.01369,-0.01676,0.01437,-0.01646,0.01500,-0.01606,0.01557,-0.01557,0.01606,-0.01500,0.01646,-0.01437,0.01676,-0.01370,0.01694,-0.01300,0.01700,0.00000*
%
%AMMACRO26_180*
4,1,40,0.00800,-0.01200,-0.00800,-0.01200,-0.00870,-0.01194,-0.00937,-0.01176,-0.01000,-0.01146,-0.01057,-0.01106,-0.01106,-0.01057,-0.01146,-0.01000,-0.01176,-0.00937,-0.01194,-0.00870,-0.01200,-0.00800,-0.01200,0.00800,-0.01194,0.00869,-0.01176,0.00937,-0.01146,0.01000,-0.01106,0.01057,-0.01057,0.01106,-0.01000,0.01146,-0.00937,0.01176,-0.00870,0.01194,-0.00800,0.01200,0.00800,0.01200,0.00869,0.01194,0.00937,0.01176,0.01000,0.01146,0.01057,0.01106,0.01106,0.01057,0.01146,0.01000,0.01176,0.00937,0.01194,0.00869,0.01200,0.00800,0.01200,-0.00800,0.01194,-0.00870,0.01176,-0.00937,0.01146,-0.01000,0.01106,-0.01057,0.01057,-0.01106,0.01000,-0.01146,0.00937,-0.01176,0.00869,-0.01194,0.00800,-0.01200,0.00000*
%
%AMMACRO17_180*
4,1,40,-0.01100,-0.00700,-0.01100,0.00700,-0.01094,0.00769,-0.01076,0.00837,-0.01046,0.00900,-0.01006,0.00957,-0.00957,0.01006,-0.00900,0.01046,-0.00837,0.01076,-0.00770,0.01094,-0.00700,0.01100,0.00700,0.01100,0.00769,0.01094,0.00837,0.01076,0.00900,0.01046,0.00957,0.01006,0.01006,0.00957,0.01046,0.00900,0.01076,0.00837,0.01094,0.00769,0.01100,0.00700,0.01100,-0.00700,0.01094,-0.00770,0.01076,-0.00837,0.01046,-0.00900,0.01006,-0.00957,0.00957,-0.01006,0.00900,-0.01046,0.00837,-0.01076,0.00769,-0.01094,0.00700,-0.01100,-0.00700,-0.01100,-0.00770,-0.01094,-0.00837,-0.01076,-0.00900,-0.01046,-0.00957,-0.01006,-0.01006,-0.00957,-0.01046,-0.00900,-0.01076,-0.00837,-0.01094,-0.00770,-0.01100,-0.00700,0.00000*
%
%AMMACRO27_180*
4,1,40,0.01300,-0.01700,-0.01300,-0.01700,-0.01370,-0.01694,-0.01437,-0.01676,-0.01500,-0.01646,-0.01557,-0.01606,-0.01606,-0.01557,-0.01646,-0.01500,-0.01676,-0.01437,-0.01694,-0.01370,-0.01700,-0.01300,-0.01700,0.01300,-0.01694,0.01369,-0.01676,0.01437,-0.01646,0.01500,-0.01606,0.01557,-0.01557,0.01606,-0.01500,0.01646,-0.01437,0.01676,-0.01370,0.01694,-0.01300,0.01700,0.01300,0.01700,0.01369,0.01694,0.01437,0.01676,0.01500,0.01646,0.01557,0.01606,0.01606,0.01557,0.01646,0.01500,0.01676,0.01437,0.01694,0.01369,0.01700,0.01300,0.01700,-0.01300,0.01694,-0.01370,0.01676,-0.01437,0.01646,-0.01500,0.01606,-0.01557,0.01557,-0.01606,0.01500,-0.01646,0.01437,-0.01676,0.01369,-0.01694,0.01300,-0.01700,0.00000*
%
%AMMACRO18_180*
4,1,40,-0.00700,0.01100,0.00700,0.01100,0.00769,0.01094,0.00837,0.01076,0.00900,0.01046,0.00957,0.01006,0.01006,0.00957,0.01046,0.00900,0.01076,0.00837,0.01094,0.00769,0.01100,0.00700,0.01100,-0.00700,0.01094,-0.00770,0.01076,-0.00837,0.01046,-0.00900,0.01006,-0.00957,0.00957,-0.01006,0.00900,-0.01046,0.00837,-0.01076,0.00769,-0.01094,0.00700,-0.01100,-0.00700,-0.01100,-0.00770,-0.01094,-0.00837,-0.01076,-0.00900,-0.01046,-0.00957,-0.01006,-0.01006,-0.00957,-0.01046,-0.00900,-0.01076,-0.00837,-0.01094,-0.00770,-0.01100,-0.00700,-0.01100,0.00700,-0.01094,0.00769,-0.01076,0.00837,-0.01046,0.00900,-0.01006,0.00957,-0.00957,0.01006,-0.00900,0.01046,-0.00837,0.01076,-0.00770,0.01094,-0.00700,0.01100,0.00000*
%
%AMMACRO31_180*
4,1,40,-0.01200,-0.00800,-0.01200,0.00800,-0.01194,0.00869,-0.01176,0.00937,-0.01146,0.01000,-0.01106,0.01057,-0.01057,0.01106,-0.01000,0.01146,-0.00937,0.01176,-0.00870,0.01194,-0.00800,0.01200,0.00800,0.01200,0.00869,0.01194,0.00937,0.01176,0.01000,0.01146,0.01057,0.01106,0.01106,0.01057,0.01146,0.01000,0.01176,0.00937,0.01194,0.00869,0.01200,0.00800,0.01200,-0.00800,0.01194,-0.00870,0.01176,-0.00937,0.01146,-0.01000,0.01106,-0.01057,0.01057,-0.01106,0.01000,-0.01146,0.00937,-0.01176,0.00869,-0.01194,0.00800,-0.01200,-0.00800,-0.01200,-0.00870,-0.01194,-0.00937,-0.01176,-0.01000,-0.01146,-0.01057,-0.01106,-0.01106,-0.01057,-0.01146,-0.01000,-0.01176,-0.00937,-0.01194,-0.00870,-0.01200,-0.00800,0.00000*
%
%AMMACRO22_180*
4,1,40,-0.01300,0.01700,0.01300,0.01700,0.01369,0.01694,0.01437,0.01676,0.01500,0.01646,0.01557,0.01606,0.01606,0.01557,0.01646,0.01500,0.01676,0.01437,0.01694,0.01369,0.01700,0.01300,0.01700,-0.01300,0.01694,-0.01370,0.01676,-0.01437,0.01646,-0.01500,0.01606,-0.01557,0.01557,-0.01606,0.01500,-0.01646,0.01437,-0.01676,0.01369,-0.01694,0.01300,-0.01700,-0.01300,-0.01700,-0.01370,-0.01694,-0.01437,-0.01676,-0.01500,-0.01646,-0.01557,-0.01606,-0.01606,-0.01557,-0.01646,-0.01500,-0.01676,-0.01437,-0.01694,-0.01370,-0.01700,-0.01300,-0.01700,0.01300,-0.01694,0.01369,-0.01676,0.01437,-0.01646,0.01500,-0.01606,0.01557,-0.01557,0.01606,-0.01500,0.01646,-0.01437,0.01676,-0.01370,0.01694,-0.01300,0.01700,0.00000*
%
%AMMACRO13_180*
4,1,40,0.01100,0.00700,0.01100,-0.00700,0.01094,-0.00770,0.01076,-0.00837,0.01046,-0.00900,0.01006,-0.00957,0.00957,-0.01006,0.00900,-0.01046,0.00837,-0.01076,0.00769,-0.01094,0.00700,-0.01100,-0.00700,-0.01100,-0.00770,-0.01094,-0.00837,-0.01076,-0.00900,-0.01046,-0.00957,-0.01006,-0.01006,-0.00957,-0.01046,-0.00900,-0.01076,-0.00837,-0.01094,-0.00770,-0.01100,-0.00700,-0.01100,0.00700,-0.01094,0.00769,-0.01076,0.00837,-0.01046,0.00900,-0.01006,0.00957,-0.00957,0.01006,-0.00900,0.01046,-0.00837,0.01076,-0.00770,0.01094,-0.00700,0.01100,0.00700,0.01100,0.00769,0.01094,0.00837,0.01076,0.00900,0.01046,0.00957,0.01006,0.01006,0.00957,0.01046,0.00900,0.01076,0.00837,0.01094,0.00769,0.01100,0.00700,0.00000*
%
%AMMACRO29_180*
4,1,40,-0.01200,-0.00800,-0.01200,0.00800,-0.01194,0.00869,-0.01176,0.00937,-0.01146,0.01000,-0.01106,0.01057,-0.01057,0.01106,-0.01000,0.01146,-0.00937,0.01176,-0.00870,0.01194,-0.00800,0.01200,0.00800,0.01200,0.00869,0.01194,0.00937,0.01176,0.01000,0.01146,0.01057,0.01106,0.01106,0.01057,0.01146,0.01000,0.01176,0.00937,0.01194,0.00869,0.01200,0.00800,0.01200,-0.00800,0.01194,-0.00870,0.01176,-0.00937,0.01146,-0.01000,0.01106,-0.01057,0.01057,-0.01106,0.01000,-0.01146,0.00937,-0.01176,0.00869,-0.01194,0.00800,-0.01200,-0.00800,-0.01200,-0.00870,-0.01194,-0.00937,-0.01176,-0.01000,-0.01146,-0.01057,-0.01106,-0.01106,-0.01057,-0.01146,-0.01000,-0.01176,-0.00937,-0.01194,-0.00870,-0.01200,-0.00800,0.00000*
%
%ADD11C,0.08600*%
%ADD13C,0.02800*%
%ADD14MACRO14*%
%ADD17MACRO17*%
%ADD18MACRO18*%
%ADD20MACRO20*%
%ADD22R,0.05500X0.04500*%
%ADD24MACRO24*%
%ADD26MACRO26*%
%ADD27MACRO27*%
%ADD29R,0.04500X0.05500*%
%ADD33R,0.01600X0.04800*%
%ADD36R,0.06900X0.02000*%
%ADD37R,0.07300X0.03500*%
%ADD39R,0.15700X0.15000*%
%ADD40C,0.02000*%
%ADD41C,0.00600*%
%ADD46C,0.04000*%
%ADD47MACRO13*%
%ADD48MACRO29*%
%ADD49MACRO22*%
%ADD50MACRO31*%
%ADD159MACRO20_180*%
%ADD162R,0.05500X0.04500*%
%ADD164MACRO14_180*%
%ADD165R,0.01600X0.04800*%
%ADD167MACRO24_180*%
%ADD171MACRO26_180*%
%ADD172MACRO17_180*%
%ADD173R,0.06900X0.02000*%
%ADD174MACRO27_180*%
%ADD175MACRO18_180*%
%ADD176R,0.07300X0.03500*%
%ADD179R,0.04500X0.05500*%
%ADD180R,0.15700X0.15000*%
%ADD181MACRO31_180*%
%ADD182MACRO22_180*%
%ADD183MACRO13_180*%
%ADD184MACRO29_180*%
%LNBSMD.art*%
%LPD*%
G54D11*
X26087Y-114844D03*
X26435Y373984D03*
X175335Y62719D03*
Y189062D03*
X547104Y69007D03*
Y195351D03*
X696192Y373984D03*
G54D20*
X119800Y293000D03*
X205800Y309500D03*
X254800Y88500D03*
X245300Y156500D03*
Y152500D03*
X254800Y197000D03*
G54D46*
X22401Y341025D03*
X291000Y22500D03*
X316610Y341025D03*
G54D22*
X155811Y305700D03*
Y313300D03*
G54D33*
X270940Y162250D03*
Y155750D03*
X273500Y162250D03*
X276060D03*
Y155750D03*
G54D13*
X62500Y279500D03*
X67050Y338239D03*
X96400Y292250D03*
X100250Y324750D03*
X122500Y296600D03*
X112500Y302000D03*
X120750Y324544D03*
X107300Y317000D03*
X118500Y318500D03*
X111400Y311750D03*
X109500Y330500D03*
X119500Y330000D03*
X135000Y293000D03*
X136500Y311500D03*
X139500Y321000D03*
X125100Y340250D03*
X161311Y302000D03*
X165811Y308000D03*
X163500Y313300D03*
X181061Y302000D03*
X177811Y309500D03*
X173811Y324500D03*
Y315000D03*
X195561Y304250D03*
X202911Y296500D03*
X237500Y92000D03*
X239500Y43500D03*
X249000Y65000D03*
X252000Y82338D03*
X252500Y103000D03*
X249000Y132500D03*
X254500Y148500D03*
X255500Y153500D03*
X240500Y150000D03*
X240437Y161999D03*
X240300Y168500D03*
X252000Y191000D03*
X249000Y185000D03*
X252500Y211500D03*
X249000Y241000D03*
X244000Y277500D03*
X259500Y82338D03*
X257000Y92500D03*
X256500Y100000D03*
Y106000D03*
X267000Y131693D03*
X259500Y191000D03*
X256500Y208500D03*
Y201000D03*
Y214500D03*
X266500Y244000D03*
X263000Y318500D03*
X284000Y107392D03*
X274750Y140500D03*
X283000Y143000D03*
X284662Y170000D03*
X287500Y186500D03*
X276500Y197000D03*
X295311Y123500D03*
X290500Y139875D03*
X294000Y166500D03*
X316500Y249500D03*
Y320500D03*
G54D50*
X258800Y164500D03*
G54D49*
X143511Y313500D03*
X205011Y314000D03*
G54D47*
X99000Y284200D03*
X95000D03*
X110000D03*
X114000D03*
X117500Y341200D03*
X121500D03*
X168311Y301700D03*
X172311D03*
X176311D03*
X199811Y304200D03*
X233311Y152700D03*
X229311Y160200D03*
X233311Y167700D03*
X264500Y164700D03*
X266500Y240200D03*
X270500D03*
G54D36*
X320394Y46752D03*
Y49902D03*
Y53051D03*
Y56201D03*
Y59351D03*
Y62500D03*
Y65650D03*
Y68799D03*
Y71949D03*
Y75099D03*
Y78248D03*
Y81398D03*
Y84548D03*
Y87697D03*
Y90847D03*
Y93996D03*
Y97146D03*
Y100296D03*
Y103445D03*
Y106595D03*
Y109744D03*
Y112894D03*
Y116044D03*
Y119193D03*
Y122343D03*
Y125492D03*
Y128642D03*
X310118Y120670D03*
Y123820D03*
Y126969D03*
X320394Y131792D03*
Y134941D03*
Y138091D03*
Y141240D03*
Y144390D03*
X310118Y130119D03*
Y133268D03*
Y136418D03*
X320394Y147540D03*
Y150689D03*
Y153839D03*
Y156988D03*
Y160138D03*
Y163288D03*
Y166437D03*
Y169587D03*
G54D14*
X99000Y280800D03*
X95000D03*
X110000D03*
X114000D03*
X117500Y337800D03*
X121500D03*
X168311Y298300D03*
X172311D03*
X176311D03*
X199811Y300800D03*
X233311Y149300D03*
X229311Y156800D03*
X233311Y164300D03*
X264500Y161300D03*
X266500Y236800D03*
X270500D03*
G54D24*
X149111Y313500D03*
X210611Y314000D03*
G54D17*
X100000Y292300D03*
X100500Y302300D03*
X96500D03*
X104500D03*
X92500D03*
X119000Y308300D03*
X115000D03*
X109000Y337800D03*
X113500D03*
X218311Y304300D03*
X233311Y156800D03*
X229311Y149300D03*
Y164300D03*
X282500Y161300D03*
G54D37*
X310315Y46142D03*
Y51142D03*
Y56142D03*
Y61142D03*
Y66142D03*
Y71142D03*
Y76142D03*
Y81142D03*
Y86142D03*
Y91142D03*
Y96142D03*
Y101142D03*
Y106142D03*
Y111142D03*
Y116142D03*
Y141142D03*
Y146142D03*
Y151142D03*
Y156142D03*
Y161142D03*
Y166142D03*
Y171142D03*
G54D26*
X222311Y307800D03*
X264500Y156800D03*
G54D39*
X334252Y13307D03*
Y203977D03*
G54D26*
X222311Y304200D03*
X264500Y153200D03*
G54D17*
X100000Y295700D03*
X100500Y305700D03*
X96500D03*
X104500D03*
X92500D03*
X119000Y311700D03*
X115000D03*
X109000Y341200D03*
X113500D03*
X218311Y307700D03*
X233311Y160200D03*
X229311Y152700D03*
Y167700D03*
X282500Y164700D03*
G54D27*
X213800Y320000D03*
G54D18*
X96800Y317000D03*
Y321000D03*
X193611Y317000D03*
X254800Y96500D03*
Y205000D03*
X271300Y131500D03*
Y135500D03*
X255300Y160500D03*
G54D27*
X208200Y320000D03*
G54D18*
X100200Y317000D03*
Y321000D03*
X197011Y317000D03*
X258200Y96500D03*
X258700Y160500D03*
X258200Y205000D03*
X274700Y131500D03*
Y135500D03*
G54D20*
X123200Y293000D03*
X209200Y309500D03*
X248700Y156500D03*
Y152500D03*
X258200Y88500D03*
Y197000D03*
G54D29*
X234700Y71000D03*
Y138500D03*
Y179500D03*
Y247000D03*
X242300Y71000D03*
Y138500D03*
Y179500D03*
Y247000D03*
G54D48*
X255200Y164500D03*
G54D20*
X492831Y293000D03*
X578831Y309500D03*
X627831Y88500D03*
X618331Y156500D03*
Y152500D03*
X627831Y197000D03*
G54D46*
X395432Y341025D03*
X664031Y22500D03*
X689641Y341025D03*
G54D22*
X528842Y305700D03*
Y313300D03*
G54D33*
X643971Y162250D03*
Y155750D03*
X646531Y162250D03*
X649091D03*
Y155750D03*
G54D13*
X435531Y279500D03*
X440081Y338239D03*
X469431Y292250D03*
X473281Y324750D03*
X495531Y296600D03*
X485531Y302000D03*
X493781Y324544D03*
X480331Y317000D03*
X491531Y318500D03*
X484431Y311750D03*
X482531Y330500D03*
X492531Y330000D03*
X508031Y293000D03*
X509531Y311500D03*
X512531Y321000D03*
X498131Y340250D03*
X534342Y302000D03*
X538842Y308000D03*
X536531Y313300D03*
X554092Y302000D03*
X550842Y309500D03*
X546842Y324500D03*
Y315000D03*
X568592Y304250D03*
X575942Y296500D03*
X610531Y92000D03*
X612531Y43500D03*
X622031Y65000D03*
X625031Y82338D03*
X625531Y103000D03*
X622031Y132500D03*
X627531Y148500D03*
X628531Y153500D03*
X613531Y150000D03*
X613468Y161999D03*
X613331Y168500D03*
X625031Y191000D03*
X622031Y185000D03*
X625531Y211500D03*
X622031Y241000D03*
X617031Y277500D03*
X632531Y82338D03*
X630031Y92500D03*
X629531Y100000D03*
Y106000D03*
X640031Y131693D03*
X632531Y191000D03*
X629531Y208500D03*
Y201000D03*
Y214500D03*
X639531Y244000D03*
X636031Y318500D03*
X657031Y107392D03*
X647781Y140500D03*
X656031Y143000D03*
X657693Y170000D03*
X660531Y186500D03*
X649531Y197000D03*
X668342Y123500D03*
X663531Y139875D03*
X667031Y166500D03*
X689531Y249500D03*
Y320500D03*
G54D50*
X631831Y164500D03*
G54D49*
X516542Y313500D03*
X578042Y314000D03*
G54D47*
X472031Y284200D03*
X468031D03*
X483031D03*
X487031D03*
X490531Y341200D03*
X494531D03*
X541342Y301700D03*
X545342D03*
X549342D03*
X572842Y304200D03*
X606342Y152700D03*
X602342Y160200D03*
X606342Y167700D03*
X637531Y164700D03*
X639531Y240200D03*
X643531D03*
G54D36*
X693425Y46752D03*
Y49902D03*
Y53051D03*
Y56201D03*
Y59351D03*
Y62500D03*
Y65650D03*
Y68799D03*
Y71949D03*
Y75099D03*
Y78248D03*
Y81398D03*
Y84548D03*
Y87697D03*
Y90847D03*
Y93996D03*
Y97146D03*
Y100296D03*
Y103445D03*
Y106595D03*
Y109744D03*
Y112894D03*
Y116044D03*
Y119193D03*
Y122343D03*
Y125492D03*
Y128642D03*
X683149Y120670D03*
Y123820D03*
Y126969D03*
X693425Y131792D03*
Y134941D03*
Y138091D03*
Y141240D03*
Y144390D03*
X683149Y130119D03*
Y133268D03*
Y136418D03*
X693425Y147540D03*
Y150689D03*
Y153839D03*
Y156988D03*
Y160138D03*
Y163288D03*
Y166437D03*
Y169587D03*
G54D14*
X472031Y280800D03*
X468031D03*
X483031D03*
X487031D03*
X490531Y337800D03*
X494531D03*
X541342Y298300D03*
X545342D03*
X549342D03*
X572842Y300800D03*
X606342Y149300D03*
X602342Y156800D03*
X606342Y164300D03*
X637531Y161300D03*
X639531Y236800D03*
X643531D03*
G54D24*
X522142Y313500D03*
X583642Y314000D03*
G54D17*
X473031Y292300D03*
X473531Y302300D03*
X469531D03*
X477531D03*
X465531D03*
X492031Y308300D03*
X488031D03*
X482031Y337800D03*
X486531D03*
X591342Y304300D03*
X606342Y156800D03*
X602342Y149300D03*
Y164300D03*
X655531Y161300D03*
G54D37*
X683346Y46142D03*
Y51142D03*
Y56142D03*
Y61142D03*
Y66142D03*
Y71142D03*
Y76142D03*
Y81142D03*
Y86142D03*
Y91142D03*
Y96142D03*
Y101142D03*
Y106142D03*
Y111142D03*
Y116142D03*
Y141142D03*
Y146142D03*
Y151142D03*
Y156142D03*
Y161142D03*
Y166142D03*
Y171142D03*
G54D26*
X595342Y307800D03*
X637531Y156800D03*
G54D39*
X707283Y13307D03*
Y203977D03*
G54D26*
X595342Y304200D03*
X637531Y153200D03*
G54D17*
X473031Y295700D03*
X473531Y305700D03*
X469531D03*
X477531D03*
X465531D03*
X492031Y311700D03*
X488031D03*
X482031Y341200D03*
X486531D03*
X591342Y307700D03*
X606342Y160200D03*
X602342Y152700D03*
Y167700D03*
X655531Y164700D03*
G54D27*
X586831Y320000D03*
G54D18*
X469831Y317000D03*
Y321000D03*
X566642Y317000D03*
X627831Y96500D03*
Y205000D03*
X644331Y131500D03*
Y135500D03*
X628331Y160500D03*
G54D27*
X581231Y320000D03*
G54D18*
X473231Y317000D03*
Y321000D03*
X570042Y317000D03*
X631231Y96500D03*
X631731Y160500D03*
X631231Y205000D03*
X647731Y131500D03*
Y135500D03*
G54D20*
X496231Y293000D03*
X582231Y309500D03*
X621731Y156500D03*
Y152500D03*
X631231Y88500D03*
Y197000D03*
G54D29*
X607731Y71000D03*
Y138500D03*
Y179500D03*
Y247000D03*
X615331Y71000D03*
Y138500D03*
Y179500D03*
Y247000D03*
G54D48*
X628231Y164500D03*
G54D159*
X229609Y-34929D03*
X143609Y-51429D03*
X94609Y169571D03*
X104109Y101571D03*
Y105571D03*
X94609Y61071D03*
G54D46*
X327008Y-82954D03*
X58409Y235571D03*
X32799Y-82954D03*
G54D162*
X193598Y-47629D03*
Y-55229D03*
G54D165*
X78469Y95821D03*
Y102321D03*
X75909Y95821D03*
X73349D03*
Y102321D03*
G54D13*
X286909Y-21429D03*
X282359Y-80168D03*
X253009Y-34179D03*
X249159Y-66679D03*
X226909Y-38529D03*
X236909Y-43929D03*
X228659Y-66473D03*
X242109Y-58929D03*
X230909Y-60429D03*
X238009Y-53679D03*
X239909Y-72429D03*
X229909Y-71929D03*
X214409Y-34929D03*
X212909Y-53429D03*
X209909Y-62929D03*
X224309Y-82179D03*
X188098Y-43929D03*
X183598Y-49929D03*
X185909Y-55229D03*
X168348Y-43929D03*
X171598Y-51429D03*
X175598Y-66429D03*
Y-56929D03*
X153848Y-46179D03*
X146498Y-38429D03*
X111909Y166071D03*
X109909Y214571D03*
X100409Y193071D03*
X97409Y175733D03*
X96909Y155071D03*
X100409Y125571D03*
X94909Y109571D03*
X93909Y104571D03*
X108909Y108071D03*
X108972Y96072D03*
X109109Y89571D03*
X97409Y67071D03*
X100409Y73071D03*
X96909Y46571D03*
X100409Y17071D03*
X105409Y-19429D03*
X89909Y175733D03*
X92409Y165571D03*
X92909Y158071D03*
Y152071D03*
X82409Y126378D03*
X89909Y67071D03*
X92909Y49571D03*
Y57071D03*
Y43571D03*
X82909Y14071D03*
X86409Y-60429D03*
X65409Y150679D03*
X74659Y117571D03*
X66409Y115071D03*
X64747Y88071D03*
X61909Y71571D03*
X72909Y61071D03*
X54098Y134571D03*
X58909Y118196D03*
X55409Y91571D03*
X32909Y8571D03*
Y-62429D03*
G54D181*
X90609Y93571D03*
G54D182*
X205898Y-55429D03*
X144398Y-55929D03*
G54D183*
X250409Y-26129D03*
X254409D03*
X239409D03*
X235409D03*
X231909Y-83129D03*
X227909D03*
X181098Y-43629D03*
X177098D03*
X173098D03*
X149598Y-46129D03*
X116098Y105371D03*
X120098Y97871D03*
X116098Y90371D03*
X84909Y93371D03*
X82909Y17871D03*
X78909D03*
G54D173*
X29015Y211319D03*
Y208169D03*
Y205020D03*
Y201870D03*
Y198720D03*
Y195571D03*
Y192421D03*
Y189272D03*
Y186122D03*
Y182972D03*
Y179823D03*
Y176673D03*
Y173523D03*
Y170374D03*
Y167224D03*
Y164075D03*
Y160925D03*
Y157775D03*
Y154626D03*
Y151476D03*
Y148327D03*
Y145177D03*
Y142027D03*
Y138878D03*
Y135728D03*
Y132579D03*
Y129429D03*
X39291Y137401D03*
Y134251D03*
Y131102D03*
X29015Y126279D03*
Y123130D03*
Y119980D03*
Y116831D03*
Y113681D03*
X39291Y127952D03*
Y124803D03*
Y121653D03*
X29015Y110531D03*
Y107382D03*
Y104232D03*
Y101083D03*
Y97933D03*
Y94783D03*
Y91634D03*
Y88484D03*
G54D164*
X250409Y-22729D03*
X254409D03*
X239409D03*
X235409D03*
X231909Y-79729D03*
X227909D03*
X181098Y-40229D03*
X177098D03*
X173098D03*
X149598Y-42729D03*
X116098Y108771D03*
X120098Y101271D03*
X116098Y93771D03*
X84909Y96771D03*
X82909Y21271D03*
X78909D03*
G54D167*
X200298Y-55429D03*
X138798Y-55929D03*
G54D172*
X249409Y-34229D03*
X248909Y-44229D03*
X252909D03*
X244909D03*
X256909D03*
X230409Y-50229D03*
X234409D03*
X240409Y-79729D03*
X235909D03*
X131098Y-46229D03*
X116098Y101271D03*
X120098Y108771D03*
Y93771D03*
X66909Y96771D03*
G54D176*
X39094Y211929D03*
Y206929D03*
Y201929D03*
Y196929D03*
Y191929D03*
Y186929D03*
Y181929D03*
Y176929D03*
Y171929D03*
Y166929D03*
Y161929D03*
Y156929D03*
Y151929D03*
Y146929D03*
Y141929D03*
Y116929D03*
Y111929D03*
Y106929D03*
Y101929D03*
Y96929D03*
Y91929D03*
Y86929D03*
G54D171*
X127098Y-49729D03*
X84909Y101271D03*
G54D180*
X15157Y244764D03*
Y54094D03*
G54D171*
X127098Y-46129D03*
X84909Y104871D03*
G54D172*
X249409Y-37629D03*
X248909Y-47629D03*
X252909D03*
X244909D03*
X256909D03*
X230409Y-53629D03*
X234409D03*
X240409Y-83129D03*
X235909D03*
X131098Y-49629D03*
X116098Y97871D03*
X120098Y105371D03*
Y90371D03*
X66909Y93371D03*
G54D174*
X135609Y-61929D03*
G54D175*
X252609Y-58929D03*
Y-62929D03*
X155798Y-58929D03*
X94609Y161571D03*
Y53071D03*
X78109Y126571D03*
Y122571D03*
X94109Y97571D03*
G54D174*
X141209Y-61929D03*
G54D175*
X249209Y-58929D03*
Y-62929D03*
X152398Y-58929D03*
X91209Y161571D03*
X90709Y97571D03*
X91209Y53071D03*
X74709Y126571D03*
Y122571D03*
G54D159*
X226209Y-34929D03*
X140209Y-51429D03*
X100709Y101571D03*
Y105571D03*
X91209Y169571D03*
Y61071D03*
G54D179*
X114709Y187071D03*
Y119571D03*
Y78571D03*
Y11071D03*
X107109Y187071D03*
Y119571D03*
Y78571D03*
Y11071D03*
G54D184*
X94209Y93571D03*
G54D159*
X602640Y-34929D03*
X516640Y-51429D03*
X467640Y169571D03*
X477140Y101571D03*
Y105571D03*
X467640Y61071D03*
G54D46*
X700039Y-82954D03*
X431440Y235571D03*
X405830Y-82954D03*
G54D162*
X566629Y-47629D03*
Y-55229D03*
G54D165*
X451500Y95821D03*
Y102321D03*
X448940Y95821D03*
X446380D03*
Y102321D03*
G54D13*
X659940Y-21429D03*
X655390Y-80168D03*
X626040Y-34179D03*
X622190Y-66679D03*
X599940Y-38529D03*
X609940Y-43929D03*
X601690Y-66473D03*
X615140Y-58929D03*
X603940Y-60429D03*
X611040Y-53679D03*
X612940Y-72429D03*
X602940Y-71929D03*
X587440Y-34929D03*
X585940Y-53429D03*
X582940Y-62929D03*
X597340Y-82179D03*
X561129Y-43929D03*
X556629Y-49929D03*
X558940Y-55229D03*
X541379Y-43929D03*
X544629Y-51429D03*
X548629Y-66429D03*
Y-56929D03*
X526879Y-46179D03*
X519529Y-38429D03*
X484940Y166071D03*
X482940Y214571D03*
X473440Y193071D03*
X470440Y175733D03*
X469940Y155071D03*
X473440Y125571D03*
X467940Y109571D03*
X466940Y104571D03*
X481940Y108071D03*
X482003Y96072D03*
X482140Y89571D03*
X470440Y67071D03*
X473440Y73071D03*
X469940Y46571D03*
X473440Y17071D03*
X478440Y-19429D03*
X462940Y175733D03*
X465440Y165571D03*
X465940Y158071D03*
Y152071D03*
X455440Y126378D03*
X462940Y67071D03*
X465940Y49571D03*
Y57071D03*
Y43571D03*
X455940Y14071D03*
X459440Y-60429D03*
X438440Y150679D03*
X447690Y117571D03*
X439440Y115071D03*
X437778Y88071D03*
X434940Y71571D03*
X445940Y61071D03*
X427129Y134571D03*
X431940Y118196D03*
X428440Y91571D03*
X405940Y8571D03*
Y-62429D03*
G54D181*
X463640Y93571D03*
G54D182*
X578929Y-55429D03*
X517429Y-55929D03*
G54D183*
X623440Y-26129D03*
X627440D03*
X612440D03*
X608440D03*
X604940Y-83129D03*
X600940D03*
X554129Y-43629D03*
X550129D03*
X546129D03*
X522629Y-46129D03*
X489129Y105371D03*
X493129Y97871D03*
X489129Y90371D03*
X457940Y93371D03*
X455940Y17871D03*
X451940D03*
G54D173*
X402046Y211319D03*
Y208169D03*
Y205020D03*
Y201870D03*
Y198720D03*
Y195571D03*
Y192421D03*
Y189272D03*
Y186122D03*
Y182972D03*
Y179823D03*
Y176673D03*
Y173523D03*
Y170374D03*
Y167224D03*
Y164075D03*
Y160925D03*
Y157775D03*
Y154626D03*
Y151476D03*
Y148327D03*
Y145177D03*
Y142027D03*
Y138878D03*
Y135728D03*
Y132579D03*
Y129429D03*
X412322Y137401D03*
Y134251D03*
Y131102D03*
X402046Y126279D03*
Y123130D03*
Y119980D03*
Y116831D03*
Y113681D03*
X412322Y127952D03*
Y124803D03*
Y121653D03*
X402046Y110531D03*
Y107382D03*
Y104232D03*
Y101083D03*
Y97933D03*
Y94783D03*
Y91634D03*
Y88484D03*
G54D164*
X623440Y-22729D03*
X627440D03*
X612440D03*
X608440D03*
X604940Y-79729D03*
X600940D03*
X554129Y-40229D03*
X550129D03*
X546129D03*
X522629Y-42729D03*
X489129Y108771D03*
X493129Y101271D03*
X489129Y93771D03*
X457940Y96771D03*
X455940Y21271D03*
X451940D03*
G54D167*
X573329Y-55429D03*
X511829Y-55929D03*
G54D172*
X622440Y-34229D03*
X621940Y-44229D03*
X625940D03*
X617940D03*
X629940D03*
X603440Y-50229D03*
X607440D03*
X613440Y-79729D03*
X608940D03*
X504129Y-46229D03*
X489129Y101271D03*
X493129Y108771D03*
Y93771D03*
X439940Y96771D03*
G54D176*
X412125Y211929D03*
Y206929D03*
Y201929D03*
Y196929D03*
Y191929D03*
Y186929D03*
Y181929D03*
Y176929D03*
Y171929D03*
Y166929D03*
Y161929D03*
Y156929D03*
Y151929D03*
Y146929D03*
Y141929D03*
Y116929D03*
Y111929D03*
Y106929D03*
Y101929D03*
Y96929D03*
Y91929D03*
Y86929D03*
G54D171*
X500129Y-49729D03*
X457940Y101271D03*
G54D180*
X388188Y244764D03*
Y54094D03*
G54D171*
X500129Y-46129D03*
X457940Y104871D03*
G54D172*
X622440Y-37629D03*
X621940Y-47629D03*
X625940D03*
X617940D03*
X629940D03*
X603440Y-53629D03*
X607440D03*
X613440Y-83129D03*
X608940D03*
X504129Y-49629D03*
X489129Y97871D03*
X493129Y105371D03*
Y90371D03*
X439940Y93371D03*
G54D174*
X508640Y-61929D03*
G54D175*
X625640Y-58929D03*
Y-62929D03*
X528829Y-58929D03*
X467640Y161571D03*
Y53071D03*
X451140Y126571D03*
Y122571D03*
X467140Y97571D03*
G54D174*
X514240Y-61929D03*
G54D175*
X622240Y-58929D03*
Y-62929D03*
X525429Y-58929D03*
X464240Y161571D03*
X463740Y97571D03*
X464240Y53071D03*
X447740Y126571D03*
Y122571D03*
G54D159*
X599240Y-34929D03*
X513240Y-51429D03*
X473740Y101571D03*
Y105571D03*
X464240Y169571D03*
Y61071D03*
G54D179*
X487740Y187071D03*
Y119571D03*
Y78571D03*
Y11071D03*
X480140Y187071D03*
Y119571D03*
Y78571D03*
Y11071D03*
G54D184*
X467240Y93571D03*
G54D40*
X-176139Y-183003D02*
G75*
G03X-176139Y-183003I-12000D01*
X-181289D02*
G03X-181289Y-183003I-6850D01*
X-172139D02*
G01X-204139D01*
X-188139Y-199003D02*
G01Y-167003D01*
X-172139Y-199003D02*
G01Y-279003D01*
Y-279003D02*
G01X1178561D01*
X-172139Y-234503D02*
G01X1178561D01*
X-172139Y-199003D02*
G01X1178561D01*
X391061D02*
G01Y-279003D01*
X528561Y-199003D02*
G01Y-279003D01*
X643561Y-199003D02*
G01Y-279003D01*
X811061Y-199003D02*
G01Y-279003D01*
X981061Y-199003D02*
G01Y-279003D01*
X1178561Y-199003D02*
G01Y-279003D01*
X1210561Y-183003D02*
G01X1178561D01*
X1206561D02*
G03X1206561Y-183003I-12000D01*
X1201411D02*
G03X1201411Y-183003I-6850D01*
X1194561Y-199003D02*
G01Y-167003D01*
G54D41*
X-148956Y-251503D02*
G01Y-269003D01*
X-140222*
X-127089Y-257337D02*
G01Y-269003D01*
Y-252670D02*
G01X-127526Y-252378D01*
Y-251795*
X-127089Y-251503*
X-126652Y-251795*
Y-252378*
X-127089Y-252670*
X-112646Y-273378D02*
G01X-111117Y-274545D01*
X-109371Y-274836*
X-107843Y-274545*
X-106532Y-273087*
X-105659Y-271045*
Y-257337*
Y-259670D02*
G01X-106532Y-258503D01*
X-107843Y-257628*
X-109371Y-257337*
X-111117Y-257920*
X-112209Y-259086*
X-113083Y-261128*
X-113519Y-263170*
X-113301Y-264920*
X-112427Y-266962*
X-111117Y-268420*
X-109371Y-269003*
X-108061Y-268711*
X-106532Y-267545*
X-105659Y-266379*
X-95801Y-269003D02*
G01Y-251503D01*
Y-259961D02*
G01X-94709Y-258503D01*
X-93617Y-257628*
X-91871Y-257337*
X-90561Y-257628*
X-89032Y-258795*
X-88377Y-260545*
Y-269003*
X-74589Y-251503D02*
G01Y-269003D01*
X-77646Y-257337D02*
G01X-71532D01*
X-60801Y-269003D02*
G01Y-257337D01*
Y-260253D02*
G01X-59927Y-258795D01*
X-58617Y-257628*
X-56871Y-257337*
X-55343Y-257628*
X-54032Y-258795*
X-53377Y-260836*
Y-269003*
X-39589Y-257337D02*
G01Y-269003D01*
Y-252670D02*
G01X-40026Y-252378D01*
Y-251795*
X-39589Y-251503*
X-39152Y-251795*
Y-252378*
X-39589Y-252670*
X-25801Y-269003D02*
G01Y-257337D01*
Y-260253D02*
G01X-24927Y-258795D01*
X-23617Y-257628*
X-21871Y-257337*
X-20343Y-257628*
X-19032Y-258795*
X-18377Y-260836*
Y-269003*
X-7646Y-273378D02*
G01X-6117Y-274545D01*
X-4371Y-274836*
X-2843Y-274545*
X-1532Y-273087*
X-659Y-271045*
Y-257337*
Y-259670D02*
G01X-1532Y-258503D01*
X-2843Y-257628*
X-4371Y-257337*
X-6117Y-257920*
X-7209Y-259086*
X-8083Y-261128*
X-8519Y-263170*
X-8301Y-264920*
X-7427Y-266962*
X-6117Y-268420*
X-4371Y-269003*
X-3061Y-268711*
X-1532Y-267545*
X-659Y-266379*
X26044Y-269003D02*
G01Y-251503D01*
X31284*
X33031Y-252378*
X34341Y-254420*
X34778Y-256753*
X34341Y-259086*
X33249Y-260836*
X31284Y-261712*
X26044*
X42452Y-251503D02*
G01X47911Y-269003D01*
X53370Y-251503*
X65411D02*
G01Y-269003D01*
X60389Y-251503D02*
G01X70433D01*
X94734Y-269003D02*
G01Y-251503D01*
X100411Y-266086*
X106088Y-251503*
Y-269003*
X117911Y-269586D02*
G01X117474Y-269295D01*
Y-268711*
X117911Y-268420*
X118348Y-268711*
Y-269295*
X117911Y-269586*
X131263Y-254420D02*
G01X132573Y-252670D01*
X134101Y-251795*
X135848Y-251503*
X138031Y-252086*
X139559Y-253545*
X139996Y-255294*
X139778Y-257045*
X138904Y-258503*
X134538Y-261420*
X132573Y-263461*
X131263Y-266379*
X130826Y-269003*
X139996*
X164952D02*
G01X170411Y-251503D01*
X175870Y-269003*
X173904Y-262878D02*
G01X166917D01*
X191841Y-251503D02*
G01Y-269003D01*
Y-266379D02*
G01X190968Y-267837D01*
X189657Y-268711*
X188129Y-269003*
X186383Y-268420*
X185073Y-266962*
X184199Y-265212*
X183981Y-263170*
X184199Y-261128*
X185073Y-259378*
X186383Y-257920*
X188129Y-257337*
X189657Y-257628*
X190749Y-258212*
X191841Y-259378*
X209341Y-269003D02*
G01Y-257337D01*
Y-259378D02*
G01X208468Y-258212D01*
X207157Y-257628*
X205629Y-257337*
X204101Y-257920*
X202791Y-259086*
X201917Y-260836*
X201481Y-263170*
X201917Y-265503*
X202791Y-267253*
X204101Y-268420*
X205629Y-269003*
X207157Y-268711*
X208468Y-267837*
X209341Y-266670*
X218981Y-274836D02*
G01Y-257337D01*
Y-259961D02*
G01X220073Y-258503D01*
X221164Y-257628*
X222911Y-257337*
X224439Y-257628*
X225968Y-259086*
X226623Y-261128*
X226841Y-263170*
X226623Y-265212*
X225968Y-267253*
X224657Y-268420*
X222911Y-269003*
X221383Y-268711*
X219854Y-267837*
X218981Y-266670*
X240411Y-251503D02*
G01Y-269003D01*
X237354Y-257337D02*
G01X243468D01*
X257911Y-269003D02*
G01X256601Y-268711D01*
X255291Y-267545*
X254417Y-265503*
X253981Y-263170*
X254417Y-260836*
X255291Y-258795*
X256601Y-257628*
X257911Y-257337*
X259221Y-257628*
X260531Y-258795*
X261404Y-260836*
X261623Y-263170*
X261404Y-265503*
X260531Y-267545*
X259221Y-268711*
X257911Y-269003*
X272354D02*
G01Y-257337D01*
Y-259670D02*
G01X273446Y-258503D01*
X274538Y-257628*
X276066Y-257337*
X277157Y-257628*
X278468Y-258503*
X315214Y-252962D02*
G01X313904Y-252086D01*
X312376Y-251503*
X310629*
X308664Y-252378*
X307136Y-253836*
X306044Y-255587*
X305171Y-258503*
X304952Y-261128*
X305389Y-263753*
X306044Y-265503*
X307354Y-267253*
X308883Y-268420*
X310411Y-269003*
X311939*
X313468Y-268420*
X314778Y-267545*
X315870Y-266379*
X331841Y-269003D02*
G01Y-257337D01*
Y-259378D02*
G01X330968Y-258212D01*
X329657Y-257628*
X328129Y-257337*
X326601Y-257920*
X325291Y-259086*
X324417Y-260836*
X323981Y-263170*
X324417Y-265503*
X325291Y-267253*
X326601Y-268420*
X328129Y-269003*
X329657Y-268711*
X330968Y-267837*
X331841Y-266670*
X342354Y-269003D02*
G01Y-257337D01*
Y-259670D02*
G01X343446Y-258503D01*
X344538Y-257628*
X346066Y-257337*
X347157Y-257628*
X348468Y-258503*
X366841Y-251503D02*
G01Y-269003D01*
Y-266379D02*
G01X365968Y-267837D01*
X364657Y-268711*
X363129Y-269003*
X361383Y-268420*
X360073Y-266962*
X359199Y-265212*
X358981Y-263170*
X359199Y-261128*
X360073Y-259378*
X361383Y-257920*
X363129Y-257337*
X364657Y-257628*
X365749Y-258212*
X366841Y-259378*
X-1Y-113228D02*
G01Y-117165D01*
Y-117165D02*
G03X7873Y-125039I7874D01*
Y-125039D02*
G01X714566D01*
Y-125039D02*
G03X722440Y-117165J7874D01*
Y-117165D02*
G01Y-113228D01*
X1968Y40473D02*
G01X9842D01*
X11811Y38504D02*
G03X9842Y40473I-1969D01*
X11811Y38504D02*
G01Y-16772D01*
X9842Y-18740D02*
G03X11811Y-16772J1969D01*
X9842Y-18740D02*
G01X1968D01*
Y-18740D02*
G03X0Y-20709J-1968D01*
Y-20709D02*
G01Y-97480D01*
Y-97480D02*
G03X7874Y-105354I7874D01*
Y-105354D02*
G01X341535D01*
Y-105354D02*
G03X349409Y-97480J7874D01*
Y-97480D02*
G01Y-15748D01*
Y-15748D02*
G03X341535Y-7874I-7874D01*
Y-7874D02*
G01X141338D01*
X133464Y0D02*
G03X141338Y-7874I7874D01*
X133464Y0D02*
G01Y250197D01*
Y250197D02*
G03X125590Y258071I-7874D01*
Y258071D02*
G01X1968D01*
Y258071D02*
G03X0Y256102J-1968D01*
Y256102D02*
G01Y236673D01*
Y236673D02*
G03X1968Y234705I1968D01*
Y234705D02*
G01X28346D01*
X30315Y232736D02*
G03X28346Y234705I-1969D01*
X30315Y232736D02*
G01Y216004D01*
X28346Y214036D02*
G03X30315Y216004I1J1968D01*
X28346Y214036D02*
G01X23228D01*
Y214036D02*
G03X21259Y212067J-1969D01*
Y212067D02*
G01Y86752D01*
Y86752D02*
G03X23228Y84784I1969J1D01*
Y84784D02*
G01X28346D01*
X30315Y82815D02*
G03X28346Y84784I-1969D01*
X30315Y82815D02*
G01Y66083D01*
X28346Y64114D02*
G03X30315Y66083J1969D01*
X28346Y64114D02*
G01X1968D01*
Y64114D02*
G03X0Y62146J-1968D01*
Y62146D02*
G01Y42441D01*
Y42441D02*
G03X1968Y40473I1968D01*
X-1Y-113228D02*
G01X13591D01*
X347441Y217598D02*
G01X339567D01*
X337598Y219567D02*
G03X339567Y217598I1969D01*
X337598Y219567D02*
G01Y274843D01*
X339567Y276811D02*
G03X337598Y274843J-1969D01*
X339567Y276811D02*
G01X347441D01*
Y276811D02*
G03X349409Y278780J1968D01*
Y278780D02*
G01Y355551D01*
Y355551D02*
G03X341535Y363425I-7874D01*
Y363425D02*
G01X7874D01*
Y363425D02*
G03X0Y355551J-7874D01*
Y355551D02*
G01Y273819D01*
Y273819D02*
G03X7874Y265945I7874D01*
Y265945D02*
G01X208071D01*
X215945Y258071D02*
G03X208071Y265945I-7874D01*
X215945Y258071D02*
G01Y7874D01*
Y7874D02*
G03X223819Y0I7874D01*
Y0D02*
G01X347441D01*
Y0D02*
G03X349409Y1969J1968D01*
Y1969D02*
G01Y21398D01*
Y21398D02*
G03X347441Y23366I-1968D01*
Y23366D02*
G01X321063D01*
X319094Y25335D02*
G03X321063Y23366I1969D01*
X319094Y25335D02*
G01Y42067D01*
X321063Y44035D02*
G03X319094Y42067J-1969D01*
X321063Y44035D02*
G01X326181D01*
Y44035D02*
G03X328150Y46004J1969D01*
Y46004D02*
G01Y171319D01*
Y171319D02*
G03X326181Y173287I-1968D01*
Y173287D02*
G01X321063D01*
X319094Y175256D02*
G03X321063Y173287I1969D01*
X319094Y175256D02*
G01Y191988D01*
X321063Y193957D02*
G03X319094Y191988J-1969D01*
X321063Y193957D02*
G01X347441D01*
Y193957D02*
G03X349409Y195925J1968D01*
Y195925D02*
G01Y215630D01*
Y215630D02*
G03X347441Y217598I-1968D01*
X245745Y383110D02*
G01X7874D01*
Y383110D02*
G03X0Y375236J-7874D01*
Y375236D02*
G01Y371299D01*
Y371299D02*
G01X13591D01*
Y-113228D02*
G03X13591Y-105354J3937D01*
Y258071D02*
G03X13591Y265945J3937D01*
Y363425D02*
G03X13591Y371299J3937D01*
X38787Y-113228D02*
G01X237000D01*
X38787Y-105354D02*
G03X38787Y-113228I1J-3937D01*
Y265945D02*
G03X38787Y258071I1J-3937D01*
X237000Y371299D02*
G01X38787D01*
Y371299D02*
G03X38787Y363425I1J-3937D01*
X68484Y-224003D02*
G01Y-206503D01*
X74161Y-221086*
X79838Y-206503*
Y-224003*
X91661D02*
G01X90351Y-223711D01*
X89041Y-222545*
X88167Y-220503*
X87731Y-218170*
X88167Y-215836*
X89041Y-213795*
X90351Y-212628*
X91661Y-212337*
X92971Y-212628*
X94281Y-213795*
X95154Y-215836*
X95373Y-218170*
X95154Y-220503*
X94281Y-222545*
X92971Y-223711*
X91661Y-224003*
X113091Y-206503D02*
G01Y-224003D01*
Y-221379D02*
G01X112218Y-222837D01*
X110907Y-223711*
X109379Y-224003*
X107633Y-223420*
X106323Y-221962*
X105449Y-220212*
X105231Y-218170*
X105449Y-216128*
X106323Y-214378*
X107633Y-212920*
X109379Y-212337*
X110907Y-212628*
X111999Y-213212*
X113091Y-214378*
X123386Y-216128D02*
G01X130373D01*
X129718Y-214086*
X128626Y-212920*
X127098Y-212337*
X125569Y-212628*
X124259Y-213503*
X123386Y-215545*
X122949Y-217295*
Y-219045*
X123386Y-220795*
X124478Y-222545*
X125788Y-223711*
X127316Y-224003*
X128844Y-223420*
X130373Y-221670*
X144161Y-224003D02*
G01Y-206503D01*
X141338Y116437D02*
G03X133464Y116437I-3937D01*
Y141634D02*
G03X141338Y141634I3937D01*
Y0D02*
G01Y116437D01*
X162106Y0D02*
G01X141337D01*
X141338Y141634D02*
G01Y258071D01*
Y258071D02*
G01X162106D01*
Y-7874D02*
G03X162106Y0J3937D01*
X179626Y62719D02*
G03X171044Y62719I-4291D01*
Y62719D02*
G03X179626Y62719I4291D01*
Y189063D02*
G03X171044Y189062I-4291D01*
Y189062D02*
G03X179626Y189063I4291J1D01*
X162106Y258071D02*
G03X162106Y265945J3937D01*
X187302Y0D02*
G03X187302Y-7874I1J-3937D01*
X208071Y0D02*
G01X187302D01*
Y265945D02*
G03X187302Y258071I1J-3937D01*
Y258071D02*
G01X208071D01*
X207913Y0D02*
G01X208071D01*
Y116437D02*
G01Y0D01*
X215945Y116437D02*
G03X208071Y116437I-3937D01*
Y141634D02*
G03X215945Y141634I3937D01*
X208071Y258071D02*
G01Y141634D01*
X237000Y-113228D02*
G03X237000Y-105354J3937D01*
Y363425D02*
G03X237000Y371299J3937D01*
X245745Y383110D02*
G03X253619Y383110I3937D01*
X722440Y371299D02*
G01Y375236D01*
Y375236D02*
G03X714566Y383110I-7874D01*
Y383110D02*
G01X253619D01*
X262196Y-113228D02*
G01X460244D01*
X262196Y-105354D02*
G03X262196Y-113228J-3937D01*
Y371299D02*
G01X460244D01*
X262196D02*
G03X262196Y363425J-3937D01*
X310621Y-7874D02*
G03X310621Y0J3937D01*
X335817D02*
G03X335817Y-7874I1J-3937D01*
X353346Y-47481D02*
G03X349409Y-51418J-3937D01*
Y-20709D02*
G03X353346Y-24646I3937D01*
Y282717D02*
G03X349409Y278780J-3937D01*
Y309489D02*
G03X353346Y305552I3937D01*
Y-47481D02*
G01X369094D01*
X373031Y-51418D02*
G03X369094Y-47481I-3937D01*
X353346Y-24646D02*
G01X369094D01*
Y-24646D02*
G03X373031Y-20709J3937D01*
X353346Y282717D02*
G01X369094D01*
X373031Y278780D02*
G03X369094Y282717I-3937D01*
X353346Y305552D02*
G01X369094D01*
Y305552D02*
G03X373031Y309489J3937D01*
X374999Y40473D02*
G01X382873D01*
X384842Y38504D02*
G03X382873Y40473I-1969D01*
X384842Y38504D02*
G01Y-16772D01*
X382873Y-18740D02*
G03X384842Y-16772J1969D01*
X382873Y-18740D02*
G01X374999D01*
Y-18740D02*
G03X373031Y-20709J-1968D01*
Y-20709D02*
G01Y-97480D01*
Y-97480D02*
G03X380905Y-105354I7874D01*
Y-105354D02*
G01X714566D01*
Y-105354D02*
G03X722440Y-97480J7874D01*
Y-97480D02*
G01Y-15748D01*
Y-15748D02*
G03X714566Y-7874I-7874D01*
Y-7874D02*
G01X514369D01*
X506495Y0D02*
G03X514369Y-7874I7874D01*
X506495Y0D02*
G01Y250197D01*
Y250197D02*
G03X498621Y258071I-7874D01*
Y258071D02*
G01X374999D01*
Y258071D02*
G03X373031Y256102J-1968D01*
Y256102D02*
G01Y236673D01*
Y236673D02*
G03X374999Y234705I1968D01*
Y234705D02*
G01X401377D01*
X403346Y232736D02*
G03X401377Y234705I-1969D01*
X403346Y232736D02*
G01Y216004D01*
X401377Y214036D02*
G03X403346Y216004I1J1968D01*
X401377Y214036D02*
G01X396259D01*
Y214036D02*
G03X394290Y212067J-1969D01*
Y212067D02*
G01Y86752D01*
Y86752D02*
G03X396259Y84784I1969J1D01*
Y84784D02*
G01X401377D01*
X403346Y82815D02*
G03X401377Y84784I-1969D01*
X403346Y82815D02*
G01Y66083D01*
X401377Y64114D02*
G03X403346Y66083J1969D01*
X401377Y64114D02*
G01X374999D01*
Y64114D02*
G03X373031Y62146J-1968D01*
Y62146D02*
G01Y42441D01*
Y42441D02*
G03X374999Y40473I1968D01*
X720472Y217598D02*
G01X712598D01*
X710629Y219567D02*
G03X712598Y217598I1969D01*
X710629Y219567D02*
G01Y274843D01*
X712598Y276811D02*
G03X710629Y274843J-1969D01*
X712598Y276811D02*
G01X720472D01*
Y276811D02*
G03X722440Y278780J1968D01*
Y278780D02*
G01Y355551D01*
Y355551D02*
G03X714566Y363425I-7874D01*
Y363425D02*
G01X380905D01*
Y363425D02*
G03X373031Y355551J-7874D01*
Y355551D02*
G01Y273819D01*
Y273819D02*
G03X380905Y265945I7874D01*
Y265945D02*
G01X581102D01*
X588976Y258071D02*
G03X581102Y265945I-7874D01*
X588976Y258071D02*
G01Y7874D01*
Y7874D02*
G03X596850Y0I7874D01*
Y0D02*
G01X720472D01*
Y0D02*
G03X722440Y1969J1968D01*
Y1969D02*
G01Y21398D01*
Y21398D02*
G03X720472Y23366I-1968D01*
Y23366D02*
G01X694094D01*
X692125Y25335D02*
G03X694094Y23366I1969D01*
X692125Y25335D02*
G01Y42067D01*
X694094Y44035D02*
G03X692125Y42067J-1969D01*
X694094Y44035D02*
G01X699212D01*
Y44035D02*
G03X701181Y46004J1969D01*
Y46004D02*
G01Y171319D01*
Y171319D02*
G03X699212Y173287I-1969J-1D01*
Y173287D02*
G01X694094D01*
X692125Y175256D02*
G03X694094Y173287I1969D01*
X692125Y175256D02*
G01Y191988D01*
X694094Y193957D02*
G03X692125Y191988J-1969D01*
X694094Y193957D02*
G01X720472D01*
Y193957D02*
G03X722440Y195925J1968D01*
Y195925D02*
G01Y215630D01*
Y215630D02*
G03X720472Y217598I-1968D01*
X386622Y258071D02*
G03X386622Y265945J3937D01*
X424761Y-269003D02*
G01Y-251503D01*
X422141Y-255003*
Y-269003D02*
G01X427381D01*
X437458Y-266379D02*
G01X438767Y-267837D01*
X440296Y-268711*
X442261Y-269003*
X444226Y-268420*
X445754Y-267253*
X446846Y-265212*
X447064Y-262878*
X446628Y-260545*
X445536Y-259086*
X444007Y-257920*
X442479Y-257628*
X440951Y-257920*
X438986Y-259086*
X439641Y-251503*
X445536*
X459324Y-269003D02*
G01X459761Y-265212D01*
X460416Y-262003*
X461289Y-259086*
X462381Y-255878*
X464128Y-251503*
X455394*
X472458Y-266379D02*
G01X473767Y-267837D01*
X475296Y-268711*
X477261Y-269003*
X479226Y-268420*
X480754Y-267253*
X481846Y-265212*
X482064Y-262878*
X481628Y-260545*
X480536Y-259086*
X479007Y-257920*
X477479Y-257628*
X475951Y-257920*
X473986Y-259086*
X474641Y-251503*
X480536*
X494761D02*
G01X493014Y-252086D01*
X491704Y-253545*
X490831Y-255294*
X490176Y-257628*
X489958Y-260253*
X490176Y-262878*
X490831Y-265212*
X491704Y-266962*
X493014Y-268420*
X494761Y-269003*
X496507Y-268420*
X497818Y-266962*
X498691Y-265212*
X499346Y-262878*
X499564Y-260253*
X499346Y-257628*
X498691Y-255294*
X497818Y-253545*
X496507Y-252086*
X494761Y-251503*
X411644Y-224003D02*
G01Y-206503D01*
X416884*
X418631Y-207378*
X419941Y-209420*
X420378Y-211753*
X419941Y-214086*
X418849Y-215836*
X416884Y-216712*
X411644*
X438314Y-207962D02*
G01X437004Y-207086D01*
X435476Y-206503*
X433729*
X431764Y-207378*
X430236Y-208836*
X429144Y-210587*
X428271Y-213503*
X428052Y-216128*
X428489Y-218753*
X429144Y-220503*
X430454Y-222253*
X431983Y-223420*
X433511Y-224003*
X435039*
X436568Y-223420*
X437878Y-222545*
X438970Y-221379*
X452757Y-214670D02*
G01X453631Y-213795D01*
X454286Y-212337*
X454723Y-210294*
X454286Y-208545*
X453413Y-207378*
X451884Y-206503*
X445989*
Y-224003*
X453194*
X454723Y-222837*
X455596Y-221086*
X456033Y-219045*
X455596Y-217003*
X454286Y-215253*
X452757Y-214670*
X445989*
X461961Y-229836D02*
G01X475061D01*
X480989Y-224003D02*
G01Y-206503D01*
X491033Y-224003*
Y-206503*
X503511Y-224003D02*
G01X501764Y-223711D01*
X500236Y-222545*
X498926Y-220795*
X498052Y-218753*
X497616Y-216420*
Y-214086*
X498052Y-211753*
X498926Y-209711*
X500236Y-207962*
X501764Y-206795*
X503511Y-206503*
X505257Y-206795*
X506786Y-207962*
X508096Y-209711*
X508970Y-211753*
X509406Y-214086*
Y-216420*
X508970Y-218753*
X508096Y-220795*
X506786Y-222545*
X505257Y-223711*
X503511Y-224003*
X411819Y265945D02*
G03X411819Y258071J-3937D01*
X460244Y-113228D02*
G03X460244Y-105354J3937D01*
Y363425D02*
G03X460244Y371299J3937D01*
X485441Y-105354D02*
G03X485441Y-113228J-3937D01*
Y371299D02*
G03X485441Y363425J-3937D01*
Y-113228D02*
G01X683652D01*
X485441Y371299D02*
G01X683652D01*
X514369Y0D02*
G01Y116437D01*
X535137Y0D02*
G01X514369D01*
Y116437D02*
G03X506494Y116437I-3937D01*
Y141634D02*
G03X514369Y141634I3938D01*
Y141634D02*
G01Y258071D01*
Y258071D02*
G01X535137D01*
Y-7874D02*
G03X535137Y0J3937D01*
X551396Y69008D02*
G03X542813Y69008I-4291D01*
Y69008D02*
G03X551396Y69008I4292D01*
Y195351D02*
G03X542813Y195352I-4292D01*
Y195352D02*
G03X551396Y195351I4291J-1D01*
X535137Y258071D02*
G03X535137Y265945J3937D01*
X554352Y-206503D02*
G01X559811Y-224003D01*
X565270Y-206503*
X581678Y-224003D02*
G01X572944D01*
Y-206503*
X581678*
X578184Y-214961D02*
G01X572944D01*
X590444Y-224003D02*
G01Y-206503D01*
X595903*
X597649Y-207378*
X598741Y-208545*
X599178Y-210878*
X598741Y-213212*
X597431Y-214670*
X595903Y-215545*
X590444*
X595903D02*
G01X599178Y-224003D01*
X612311Y-224586D02*
G01X611874Y-224295D01*
Y-223711*
X612311Y-223420*
X612748Y-223711*
Y-224295*
X612311Y-224586*
X560333Y0D02*
G03X560333Y-7874I1J-3937D01*
X581102Y0D02*
G01X560333D01*
Y265945D02*
G03X560333Y258071I1J-3937D01*
Y258071D02*
G01X581102D01*
X586061Y-269003D02*
G01Y-251503D01*
X583441Y-255003*
Y-269003D02*
G01X588681D01*
X581102Y116437D02*
G01Y0D01*
X588976Y116437D02*
G03X581102Y116437I-3937D01*
Y141634D02*
G03X588976Y141634I3937D01*
X581102Y258071D02*
G01Y141634D01*
X751765Y-259670D02*
G01X750891Y-258795D01*
X750236Y-257337*
X749799Y-255294*
X750236Y-253545*
X751109Y-252378*
X752638Y-251503*
X758533*
Y-269003*
X751328*
X749799Y-267837*
X748926Y-266086*
X748489Y-264045*
X748926Y-262003*
X750236Y-260253*
X751765Y-259670*
X758533*
X740596Y-266670D02*
G01X738849Y-268128D01*
X736884Y-269003*
X735138*
X733391Y-268128*
X732081Y-266670*
X731426Y-264628*
X731863Y-262587*
X732954Y-260836*
X734919Y-259670*
X737539Y-259086*
X739068Y-257920*
X739723Y-255878*
X739286Y-253836*
X738194Y-252378*
X736666Y-251503*
X735138*
X733609Y-252086*
X732299Y-253545*
X724188Y-269003D02*
G01Y-251503D01*
X718511Y-266086*
X712834Y-251503*
Y-269003*
X705814D02*
G01Y-251503D01*
X701448*
X699701Y-252378*
X698391Y-253545*
X697299Y-255294*
X696426Y-257337*
X696208Y-260253*
X696426Y-263170*
X697299Y-265212*
X698391Y-266962*
X699701Y-268128*
X701448Y-269003*
X705814*
X687894Y-206503D02*
G01Y-224003D01*
X696628*
X713691D02*
G01Y-212337D01*
Y-214378D02*
G01X712818Y-213212D01*
X711507Y-212628*
X709979Y-212337*
X708451Y-212920*
X707141Y-214086*
X706267Y-215836*
X705831Y-218170*
X706267Y-220503*
X707141Y-222253*
X708451Y-223420*
X709979Y-224003*
X711507Y-223711*
X712818Y-222837*
X713691Y-221670*
X722676Y-229253D02*
G01X723986Y-229836D01*
X725733Y-229253*
X726824Y-228087*
X727698Y-226628*
X729007Y-221962*
X731846Y-212337*
X724859D02*
G01X729007Y-221962D01*
X741486Y-216128D02*
G01X748473D01*
X747818Y-214086*
X746726Y-212920*
X745198Y-212337*
X743669Y-212628*
X742359Y-213503*
X741486Y-215545*
X741049Y-217295*
Y-219045*
X741486Y-220795*
X742578Y-222545*
X743888Y-223711*
X745416Y-224003*
X746944Y-223420*
X748473Y-221670*
X759204Y-224003D02*
G01Y-212337D01*
Y-214670D02*
G01X760296Y-213503D01*
X761388Y-212628*
X762916Y-212337*
X764007Y-212628*
X765318Y-213503*
X683652Y-113228D02*
G03X683652Y-105354J3937D01*
Y-7874D02*
G03X683652Y0J3937D01*
Y363425D02*
G03X683652Y371299J3937D01*
X708848Y-113228D02*
G01X722440D01*
X708848Y-105354D02*
G03X708848Y-113228I1J-3937D01*
Y0D02*
G03X708848Y-7874I1J-3937D01*
Y371299D02*
G01X722440D01*
X708848D02*
G03X708848Y363425I1J-3937D01*
X830008Y-224003D02*
G01Y-206503D01*
X834374*
X836121Y-207378*
X837431Y-208545*
X838523Y-210294*
X839396Y-212337*
X839614Y-215253*
X839396Y-218170*
X838523Y-220212*
X837431Y-221962*
X836121Y-223128*
X834374Y-224003*
X830008*
X849036Y-216128D02*
G01X856023D01*
X855368Y-214086*
X854276Y-212920*
X852748Y-212337*
X851219Y-212628*
X849909Y-213503*
X849036Y-215545*
X848599Y-217295*
Y-219045*
X849036Y-220795*
X850128Y-222545*
X851438Y-223711*
X852966Y-224003*
X854494Y-223420*
X856023Y-221670*
X866536Y-221962D02*
G01X867628Y-223128D01*
X869156Y-224003*
X870466*
X871776Y-223420*
X872649Y-222545*
X873086Y-221379*
X872868Y-219628*
X871994Y-218753*
X868064Y-217003*
X867191Y-214961*
X867628Y-213503*
X868501Y-212628*
X869811Y-212337*
X871121Y-212628*
X872431Y-213503*
X887311Y-212337D02*
G01Y-224003D01*
Y-207670D02*
G01X886874Y-207378D01*
Y-206795*
X887311Y-206503*
X887748Y-206795*
Y-207378*
X887311Y-207670*
X901754Y-228378D02*
G01X903283Y-229545D01*
X905029Y-229836*
X906557Y-229545*
X907868Y-228087*
X908741Y-226045*
Y-212337*
Y-214670D02*
G01X907868Y-213503D01*
X906557Y-212628*
X905029Y-212337*
X903283Y-212920*
X902191Y-214086*
X901317Y-216128*
X900881Y-218170*
X901099Y-219920*
X901973Y-221962*
X903283Y-223420*
X905029Y-224003*
X906339Y-223711*
X907868Y-222545*
X908741Y-221379*
X918599Y-224003D02*
G01Y-212337D01*
Y-215253D02*
G01X919473Y-213795D01*
X920783Y-212628*
X922529Y-212337*
X924057Y-212628*
X925368Y-213795*
X926023Y-215836*
Y-224003*
X936536Y-216128D02*
G01X943523D01*
X942868Y-214086*
X941776Y-212920*
X940248Y-212337*
X938719Y-212628*
X937409Y-213503*
X936536Y-215545*
X936099Y-217295*
Y-219045*
X936536Y-220795*
X937628Y-222545*
X938938Y-223711*
X940466Y-224003*
X941994Y-223420*
X943523Y-221670*
X954254Y-224003D02*
G01Y-212337D01*
Y-214670D02*
G01X955346Y-213503D01*
X956438Y-212628*
X957966Y-212337*
X959057Y-212628*
X960368Y-213503*
X874194Y-265503D02*
G01X875286Y-267253D01*
X876596Y-268420*
X878124Y-269003*
X879871Y-268420*
X881181Y-267253*
X882491Y-265503*
X882928Y-263170*
Y-251503*
X896061Y-269003D02*
G01X894314Y-268711D01*
X892786Y-267545*
X891476Y-265795*
X890602Y-263753*
X890166Y-261420*
Y-259086*
X890602Y-256753*
X891476Y-254711*
X892786Y-252962*
X894314Y-251795*
X896061Y-251503*
X897807Y-251795*
X899336Y-252962*
X900646Y-254711*
X901520Y-256753*
X901956Y-259086*
Y-261420*
X901520Y-263753*
X900646Y-265795*
X899336Y-267545*
X897807Y-268711*
X896061Y-269003*
X913561D02*
G01Y-261128D01*
X909194Y-251503*
X917928D02*
G01X913561Y-261128D01*
X1001011Y-269003D02*
G01Y-251503D01*
X998391Y-255003*
Y-269003D02*
G01X1003631D01*
X1014363Y-254420D02*
G01X1015673Y-252670D01*
X1017201Y-251795*
X1018948Y-251503*
X1021131Y-252086*
X1022659Y-253545*
X1023096Y-255294*
X1022878Y-257045*
X1022004Y-258503*
X1017638Y-261420*
X1015673Y-263461*
X1014363Y-266379*
X1013926Y-269003*
X1023096*
X1032081Y-269586D02*
G01X1039941Y-251503D01*
X1048708Y-265503D02*
G01X1050017Y-267545D01*
X1051764Y-268711*
X1053729Y-269003*
X1055476Y-268711*
X1057223Y-267253*
X1058314Y-265503*
X1058533Y-263753*
X1058096Y-261712*
X1056568Y-260253*
X1055039Y-259670*
X1053074*
X1055039D02*
G01X1056349Y-258795D01*
X1057441Y-257337*
X1057878Y-255587*
X1057441Y-253836*
X1056349Y-252378*
X1054384Y-251503*
X1052419Y-251795*
X1050454Y-252962*
X1071011Y-251503D02*
G01X1069264Y-252086D01*
X1067954Y-253545*
X1067081Y-255294*
X1066426Y-257628*
X1066208Y-260253*
X1066426Y-262878*
X1067081Y-265212*
X1067954Y-266962*
X1069264Y-268420*
X1071011Y-269003*
X1072757Y-268420*
X1074068Y-266962*
X1074941Y-265212*
X1075596Y-262878*
X1075814Y-260253*
X1075596Y-257628*
X1074941Y-255294*
X1074068Y-253545*
X1072757Y-252086*
X1071011Y-251503*
X1084581Y-269586D02*
G01X1092441Y-251503D01*
X1101863Y-254420D02*
G01X1103173Y-252670D01*
X1104701Y-251795*
X1106448Y-251503*
X1108631Y-252086*
X1110159Y-253545*
X1110596Y-255294*
X1110378Y-257045*
X1109504Y-258503*
X1105138Y-261420*
X1103173Y-263461*
X1101863Y-266379*
X1101426Y-269003*
X1110596*
X1123511Y-251503D02*
G01X1121764Y-252086D01*
X1120454Y-253545*
X1119581Y-255294*
X1118926Y-257628*
X1118708Y-260253*
X1118926Y-262878*
X1119581Y-265212*
X1120454Y-266962*
X1121764Y-268420*
X1123511Y-269003*
X1125257Y-268420*
X1126568Y-266962*
X1127441Y-265212*
X1128096Y-262878*
X1128314Y-260253*
X1128096Y-257628*
X1127441Y-255294*
X1126568Y-253545*
X1125257Y-252086*
X1123511Y-251503*
X1141011Y-269003D02*
G01Y-251503D01*
X1138391Y-255003*
Y-269003D02*
G01X1143631D01*
X1154363Y-261712D02*
G01X1155891Y-259670D01*
X1157201Y-258503*
X1158948Y-257920*
X1160476Y-258503*
X1161568Y-259670*
X1162441Y-261420*
X1162659Y-263461*
X1162441Y-265212*
X1161568Y-266962*
X1160257Y-268420*
X1158729Y-269003*
X1156983Y-268420*
X1155454Y-266670*
X1154581Y-264045*
X1154363Y-261128*
X1154799Y-257337*
X1155454Y-255294*
X1156546Y-253253*
X1158074Y-251795*
X1159603Y-251503*
X1161131Y-252086*
X1162223Y-253545*
X1048708Y-224003D02*
G01Y-206503D01*
X1053074*
X1054821Y-207378*
X1056131Y-208545*
X1057223Y-210294*
X1058096Y-212337*
X1058314Y-215253*
X1058096Y-218170*
X1057223Y-220212*
X1056131Y-221962*
X1054821Y-223128*
X1053074Y-224003*
X1048708*
X1074941D02*
G01Y-212337D01*
Y-214378D02*
G01X1074068Y-213212D01*
X1072757Y-212628*
X1071229Y-212337*
X1069701Y-212920*
X1068391Y-214086*
X1067517Y-215836*
X1067081Y-218170*
X1067517Y-220503*
X1068391Y-222253*
X1069701Y-223420*
X1071229Y-224003*
X1072757Y-223711*
X1074068Y-222837*
X1074941Y-221670*
X1088511Y-206503D02*
G01Y-224003D01*
X1085454Y-212337D02*
G01X1091568D01*
X1102736Y-216128D02*
G01X1109723D01*
X1109068Y-214086*
X1107976Y-212920*
X1106448Y-212337*
X1104919Y-212628*
X1103609Y-213503*
X1102736Y-215545*
X1102299Y-217295*
Y-219045*
X1102736Y-220795*
X1103828Y-222545*
X1105138Y-223711*
X1106666Y-224003*
X1108194Y-223420*
X1109723Y-221670*
X720472Y217598D02*
G01X712598D01*
X710629Y219567D02*
G03X712598Y217598I1969D01*
X710629Y219567D02*
G01Y274843D01*
X712598Y276811D02*
G03X710629Y274843J-1969D01*
X712598Y276811D02*
G01X720472D01*
Y276811D02*
G03X722440Y278780J1968D01*
Y278780D02*
G01Y355551D01*
Y355551D02*
G03X714566Y363425I-7874D01*
Y363425D02*
G01X380905D01*
Y363425D02*
G03X373031Y355551J-7874D01*
Y355551D02*
G01Y273819D01*
Y273819D02*
G03X380905Y265945I7874D01*
Y265945D02*
G01X581102D01*
X588976Y258071D02*
G03X581102Y265945I-7874D01*
X588976Y258071D02*
G01Y7874D01*
Y7874D02*
G03X596850Y0I7874D01*
Y0D02*
G01X720472D01*
Y0D02*
G03X722440Y1969J1968D01*
Y1969D02*
G01Y21398D01*
Y21398D02*
G03X720472Y23366I-1968D01*
Y23366D02*
G01X694094D01*
X692125Y25335D02*
G03X694094Y23366I1969D01*
X692125Y25335D02*
G01Y42067D01*
X694094Y44035D02*
G03X692125Y42067J-1969D01*
X694094Y44035D02*
G01X699212D01*
Y44035D02*
G03X701181Y46004J1969D01*
Y46004D02*
G01Y171319D01*
Y171319D02*
G03X699212Y173287I-1968D01*
Y173287D02*
G01X694094D01*
X692125Y175256D02*
G03X694094Y173287I1969D01*
X692125Y175256D02*
G01Y191988D01*
X694094Y193957D02*
G03X692125Y191988J-1969D01*
X694094Y193957D02*
G01X720472D01*
Y193957D02*
G03X722440Y195925J1968D01*
Y195925D02*
G01Y215630D01*
Y215630D02*
G03X720472Y217598I-1968D01*
X1968Y40473D02*
G01X9842D01*
X11811Y38504D02*
G03X9842Y40473I-1969D01*
X11811Y38504D02*
G01Y-16772D01*
X9842Y-18740D02*
G03X11811Y-16772J1969D01*
X9842Y-18740D02*
G01X1968D01*
Y-18740D02*
G03X0Y-20709J-1968D01*
Y-20709D02*
G01Y-97480D01*
Y-97480D02*
G03X7874Y-105354I7874D01*
Y-105354D02*
G01X341535D01*
Y-105354D02*
G03X349409Y-97480J7874D01*
Y-97480D02*
G01Y-15748D01*
Y-15748D02*
G03X341535Y-7874I-7874D01*
Y-7874D02*
G01X141338D01*
X133464Y0D02*
G03X141338Y-7874I7874D01*
X133464Y0D02*
G01Y250197D01*
Y250197D02*
G03X125590Y258071I-7874D01*
Y258071D02*
G01X1968D01*
Y258071D02*
G03X0Y256102J-1968D01*
Y256102D02*
G01Y236673D01*
Y236673D02*
G03X1968Y234705I1968D01*
Y234705D02*
G01X28346D01*
X30315Y232736D02*
G03X28346Y234705I-1969D01*
X30315Y232736D02*
G01Y216004D01*
X28346Y214036D02*
G03X30315Y216004J1969D01*
X28346Y214036D02*
G01X23228D01*
Y214036D02*
G03X21259Y212067J-1969D01*
Y212067D02*
G01Y86752D01*
Y86752D02*
G03X23228Y84784I1968D01*
Y84784D02*
G01X28346D01*
X30315Y82815D02*
G03X28346Y84784I-1969D01*
X30315Y82815D02*
G01Y66083D01*
X28346Y64114D02*
G03X30315Y66083J1969D01*
X28346Y64114D02*
G01X1968D01*
Y64114D02*
G03X0Y62146J-1968D01*
Y62146D02*
G01Y42441D01*
Y42441D02*
G03X1968Y40473I1968D01*
X374999D02*
G01X382873D01*
X384842Y38504D02*
G03X382873Y40473I-1969D01*
X384842Y38504D02*
G01Y-16772D01*
X382873Y-18740D02*
G03X384842Y-16772J1969D01*
X382873Y-18740D02*
G01X374999D01*
Y-18740D02*
G03X373031Y-20709J-1968D01*
Y-20709D02*
G01Y-97480D01*
Y-97480D02*
G03X380905Y-105354I7874D01*
Y-105354D02*
G01X714566D01*
Y-105354D02*
G03X722440Y-97480J7874D01*
Y-97480D02*
G01Y-15748D01*
Y-15748D02*
G03X714566Y-7874I-7874D01*
Y-7874D02*
G01X514369D01*
X506495Y0D02*
G03X514369Y-7874I7874D01*
X506495Y0D02*
G01Y250197D01*
Y250197D02*
G03X498621Y258071I-7874D01*
Y258071D02*
G01X374999D01*
Y258071D02*
G03X373031Y256102J-1968D01*
Y256102D02*
G01Y236673D01*
Y236673D02*
G03X374999Y234705I1968D01*
Y234705D02*
G01X401377D01*
X403346Y232736D02*
G03X401377Y234705I-1969D01*
X403346Y232736D02*
G01Y216004D01*
X401377Y214036D02*
G03X403346Y216004J1969D01*
X401377Y214036D02*
G01X396259D01*
Y214036D02*
G03X394290Y212067J-1969D01*
Y212067D02*
G01Y86752D01*
Y86752D02*
G03X396259Y84784I1968D01*
Y84784D02*
G01X401377D01*
X403346Y82815D02*
G03X401377Y84784I-1969D01*
X403346Y82815D02*
G01Y66083D01*
X401377Y64114D02*
G03X403346Y66083J1969D01*
X401377Y64114D02*
G01X374999D01*
Y64114D02*
G03X373031Y62146J-1968D01*
Y62146D02*
G01Y42441D01*
Y42441D02*
G03X374999Y40473I1968D01*
M02*
